# T6G (Grand Teton) — schematic netlist excerpt (pin names and nets, part order shuffled) for the footprints in the layout excerpt that follows; sources: Cadence DE-HDL packaged netlist, KiCad conversion of 04192023_DAF0TMB3IC0_F0TG_MB_C_brd_V02_OCP.brd

PC124_3  Q_CAP  22UF 16V 20% X6S  pkg C0805  page 202 : A = SW_P12V_AUX_PVDDCR_CPU1_P0_FLT ; B = GND
C457  Q_CAP  0.1UF 10V 10% X7S  pkg C0201  page 356 : A = P0V9_CPU1_RT3_2A ; B = GND
R474  Q_RES  0 5% CHIP  pkg 0402LF  page 29 : A = RST_ESPI_CPU0_RSTOUT_N ; B = RST_ESPI_CPU0_R_RSTOUT_N

(kicad_pcb
	(version 20260206)
	(generator "pcbnew")
	(generator_version "10.0")
	(general
		(thickness 1.6)
		(legacy_teardrops no)
	)
	(paper "A4")
	(title_block
		(title "04192023_DAF0TMB3IC0_F0TG_MB_C_brd_V02_OCP.brd")
		(comment 1 "Grand Teton / footprints 7775-7777 of 8354")
	)
	(layers
		(0 "F.Cu" signal "TOP")
		(4 "In1.Cu" signal "GND")
		(6 "In2.Cu" signal "IN1")
		(8 "In3.Cu" signal "GND1")
		(10 "In4.Cu" signal "IN2")
		(12 "In5.Cu" signal "GND2")
		(14 "In6.Cu" signal "IN3")
		(16 "In7.Cu" signal "GND3")
		(18 "In8.Cu" signal "VCC")
		(20 "In9.Cu" signal "VCC1")
		(22 "In10.Cu" signal "GND4")
		(24 "In11.Cu" signal "IN4")
		(26 "In12.Cu" signal "GND5")
		(28 "In13.Cu" signal "IN5")
		(30 "In14.Cu" signal "GND6")
		(32 "In15.Cu" signal "IN6")
		(34 "In16.Cu" signal "GND7")
		(2 "B.Cu" signal "BOTTOM")
		(9 "F.Adhes" user "F.Adhesive")
		(11 "B.Adhes" user "B.Adhesive")
		(13 "F.Paste" user "Package Geometry/Pastemask Top")
		(15 "B.Paste" user "Package Geometry/Pastemask Bottom")
		(5 "F.SilkS" user "Ref Des/Silkscreen Top")
		(7 "B.SilkS" user "Ref Des/Silkscreen Bottom")
		(1 "F.Mask" user "Board Geometry/Soldermask Top")
		(3 "B.Mask" user "Board Geometry/Soldermask Bottom")
		(17 "Dwgs.User" user "User.Drawings")
		(19 "Cmts.User" user "User.Comments")
		(21 "Eco1.User" user "User.Eco1")
		(23 "Eco2.User" user "User.Eco2")
		(25 "Edge.Cuts" user "Board Geometry/Outline")
		(27 "Margin" user)
		(31 "F.CrtYd" user "Package Geometry/Place Bound Top")
		(29 "B.CrtYd" user "Package Geometry/Place Bound Bottom")
		(35 "F.Fab" user "Ref Des/Assembly Top")
		(33 "B.Fab" user "Ref Des/Assembly Bottom")
	)
	(footprint ""
		(layer "B.Cu")
		(at 399.034508 -330.090272)
		(property "Reference" "R474"
			(at 0 0 0)
			(layer "B.SilkS")
			(hide yes)
			(effects
				(font
					(size 1.27 1.27)
				)
				(justify mirror)
			)
		)
		(property "Value" ""
			(at 0 0 0)
			(layer "B.Fab")
			(effects
				(font
					(size 1.27 1.27)
				)
				(justify mirror)
			)
		)
		(duplicate_pad_numbers_are_jumpers no)
		(fp_line
			(start -0.7874 -0.4064)
			(end -0.7874 0.4064)
			(stroke
				(width 0.1524)
				(type default)
			)
			(layer "B.SilkS")
		)
		(fp_line
			(start -0.7874 0.4064)
			(end 0.7874 0.4064)
			(stroke
				(width 0.1524)
				(type default)
			)
			(layer "B.SilkS")
		)
		(fp_line
			(start 0.7874 -0.4064)
			(end -0.7874 -0.4064)
			(stroke
				(width 0.1524)
				(type default)
			)
			(layer "B.SilkS")
		)
		(fp_line
			(start 0.7874 0.4064)
			(end 0.7874 -0.4064)
			(stroke
				(width 0.1524)
				(type default)
			)
			(layer "B.SilkS")
		)
		(fp_line
			(start -0.67945 -0.3048)
			(end -0.67945 0.3048)
			(stroke
				(width 0.1)
				(type default)
			)
			(layer "B.Fab")
		)
		(fp_line
			(start -0.67945 0.3048)
			(end -0.120396 0.3048)
			(stroke
				(width 0.1)
				(type default)
			)
			(layer "B.Fab")
		)
		(fp_line
			(start -0.12065 -0.3048)
			(end -0.67945 -0.3048)
			(stroke
				(width 0.1)
				(type default)
			)
			(layer "B.Fab")
		)
		(fp_line
			(start -0.12065 -0.2794)
			(end -0.12065 -0.3048)
			(stroke
				(width 0.1)
				(type default)
			)
			(layer "B.Fab")
		)
		(fp_line
			(start -0.120396 0.2794)
			(end 0.12065 0.2794)
			(stroke
				(width 0.1)
				(type default)
			)
			(layer "B.Fab")
		)
		(fp_line
			(start -0.120396 0.3048)
			(end -0.120396 0.2794)
			(stroke
				(width 0.1)
				(type default)
			)
			(layer "B.Fab")
		)
		(fp_line
			(start 0.12065 -0.305054)
			(end 0.12065 -0.2794)
			(stroke
				(width 0.1)
				(type default)
			)
			(layer "B.Fab")
		)
		(fp_line
			(start 0.12065 -0.2794)
			(end -0.12065 -0.2794)
			(stroke
				(width 0.1)
				(type default)
			)
			(layer "B.Fab")
		)
		(fp_line
			(start 0.12065 0.2794)
			(end 0.12065 0.3048)
			(stroke
				(width 0.1)
				(type default)
			)
			(layer "B.Fab")
		)
		(fp_line
			(start 0.12065 0.3048)
			(end 0.67945 0.3048)
			(stroke
				(width 0.1)
				(type default)
			)
			(layer "B.Fab")
		)
		(fp_line
			(start 0.67945 -0.305054)
			(end 0.12065 -0.305054)
			(stroke
				(width 0.1)
				(type default)
			)
			(layer "B.Fab")
		)
		(fp_line
			(start 0.67945 0.3048)
			(end 0.67945 -0.305054)
			(stroke
				(width 0.1)
				(type default)
			)
			(layer "B.Fab")
		)
		(pad "1" smd circle
			(at 0.40005 0 180)
			(size 0 0)
			(layers "B.Cu" "B.Mask" "B.Paste")
			(net "RST_ESPI_CPU0_RSTOUT_N")
		)
		(pad "2" smd circle
			(at -0.40005 0 180)
			(size 0 0)
			(layers "B.Cu" "B.Mask" "B.Paste")
			(net "RST_ESPI_CPU0_R_RSTOUT_N")
		)
	)
	(footprint ""
		(layer "B.Cu")
		(at 115.818412 -388.011162 -90)
		(property "Reference" "C457"
			(at 0 0 90)
			(layer "B.SilkS")
			(hide yes)
			(effects
				(font
					(size 1.27 1.27)
				)
				(justify mirror)
			)
		)
		(property "Value" ""
			(at 0 0 90)
			(layer "B.Fab")
			(effects
				(font
					(size 1.27 1.27)
				)
				(justify mirror)
			)
		)
		(duplicate_pad_numbers_are_jumpers no)
		(fp_line
			(start -0.299974 0.150114)
			(end 0.299974 0.150114)
			(stroke
				(width 0.1)
				(type default)
			)
			(layer "B.Fab")
		)
		(fp_line
			(start 0.299974 0.150114)
			(end 0.299974 -0.150114)
			(stroke
				(width 0.1)
				(type default)
			)
			(layer "B.Fab")
		)
		(fp_line
			(start -0.299974 -0.150114)
			(end -0.299974 0.150114)
			(stroke
				(width 0.1)
				(type default)
			)
			(layer "B.Fab")
		)
		(fp_line
			(start 0.299974 -0.150114)
			(end -0.299974 -0.150114)
			(stroke
				(width 0.1)
				(type default)
			)
			(layer "B.Fab")
		)
		(pad "1" smd rect
			(at 0.2667 0 90)
			(size 0.3048 0.381)
			(layers "B.Cu" "B.Mask" "B.Paste")
			(net "P0V9_CPU1_RT3_2A")
		)
		(pad "2" smd rect
			(at -0.2667 0 90)
			(size 0.3048 0.381)
			(layers "B.Cu" "B.Mask" "B.Paste")
			(net "GND")
		)
	)
	(footprint ""
		(layer "B.Cu")
		(at 321.595496 -335.063084 90)
		(property "Reference" "PC124_3"
			(at 0 0 90)
			(layer "B.SilkS")
			(hide yes)
			(effects
				(font
					(size 1.27 1.27)
				)
				(justify mirror)
			)
		)
		(property "Value" ""
			(at 0 0 90)
			(layer "B.Fab")
			(effects
				(font
					(size 1.27 1.27)
				)
				(justify mirror)
			)
		)
		(duplicate_pad_numbers_are_jumpers no)
		(fp_line
			(start 1.524 -0.762)
			(end -1.524 -0.762)
			(stroke
				(width 0.1524)
				(type default)
			)
			(layer "B.SilkS")
		)
		(fp_line
			(start -1.524 -0.762)
			(end -1.524 0.762)
			(stroke
				(width 0.1524)
				(type default)
			)
			(layer "B.SilkS")
		)
		(fp_line
			(start 1.524 0.762)
			(end 1.524 -0.762)
			(stroke
				(width 0.1524)
				(type default)
			)
			(layer "B.SilkS")
		)
		(fp_line
			(start -1.524 0.762)
			(end 1.524 0.762)
			(stroke
				(width 0.1524)
				(type default)
			)
			(layer "B.SilkS")
		)
		(fp_line
			(start 1.1049 -0.724916)
			(end 1.1049 0.724916)
			(stroke
				(width 0.1)
				(type default)
			)
			(layer "B.Fab")
		)
		(fp_line
			(start -1.1049 -0.724916)
			(end 1.1049 -0.724916)
			(stroke
				(width 0.1)
				(type default)
			)
			(layer "B.Fab")
		)
		(fp_line
			(start 1.1049 0.724916)
			(end -1.1049 0.724916)
			(stroke
				(width 0.1)
				(type default)
			)
			(layer "B.Fab")
		)
		(fp_line
			(start -1.1049 0.724916)
			(end -1.1049 -0.724916)
			(stroke
				(width 0.1)
				(type default)
			)
			(layer "B.Fab")
		)
		(pad "1" smd rect
			(at 0.889 0 90)
			(size 1.016 1.27)
			(layers "B.Cu" "B.Mask" "B.Paste")
			(net "SW_P12V_AUX_PVDDCR_CPU1_P0_FLT")
		)
		(pad "2" smd rect
			(at -0.889 0 90)
			(size 1.016 1.27)
			(layers "B.Cu" "B.Mask" "B.Paste")
			(net "GND")
		)
	)
)
